# S9S_MB_2U (Grand Teton) — schematic netlist excerpt (pin names and nets, part order shuffled) for the footprints in the layout excerpt that follows; sources: Cadence DE-HDL packaged netlist, KiCad conversion of 03242023_DA0F0TMBIJ0_F0T_Motherboard_J_brd_V01_OCP.brd

PC236_P0_8  Q_CAP  22UF 16V 20% X6S  pkg C0805  page 270 : A = SW_P12V_PVCCIN_CPU0_FLT ; B = GND
R1106  Q_RES  10K 1% CHIP  pkg 0402LF  page 215 : A = P3V3_AUX ; B = FM_PLD_REV_R_N
C1154  Q_CAP  0.01UF 50V 10% X7R  pkg C0402  page 217 : A = VCC_PLD_CORE ; B = GND

(kicad_pcb
	(version 20260206)
	(generator "pcbnew")
	(generator_version "10.0")
	(general
		(thickness 1.6)
		(legacy_teardrops no)
	)
	(paper "A4")
	(title_block
		(title "03242023_DA0F0TMBIJ0_F0T_Motherboard_J_brd_V01_OCP.brd")
		(comment 1 "Grand Teton / footprints 4771-4773 of 6105")
	)
	(layers
		(0 "F.Cu" signal "TOP")
		(4 "In1.Cu" signal "GND")
		(6 "In2.Cu" signal "IN1")
		(8 "In3.Cu" signal "GND1")
		(10 "In4.Cu" signal "IN2")
		(12 "In5.Cu" signal "GND2")
		(14 "In6.Cu" signal "IN3")
		(16 "In7.Cu" signal "GND3")
		(18 "In8.Cu" signal "VCC")
		(20 "In9.Cu" signal "VCC1")
		(22 "In10.Cu" signal "GND4")
		(24 "In11.Cu" signal "IN4")
		(26 "In12.Cu" signal "GND5")
		(28 "In13.Cu" signal "IN5")
		(30 "In14.Cu" signal "GND6")
		(32 "In15.Cu" signal "IN6")
		(34 "In16.Cu" signal "GND7")
		(2 "B.Cu" signal "BOTTOM")
		(9 "F.Adhes" user "F.Adhesive")
		(11 "B.Adhes" user "B.Adhesive")
		(13 "F.Paste" user "Package Geometry/Pastemask Top")
		(15 "B.Paste" user "Package Geometry/Pastemask Bottom")
		(5 "F.SilkS" user "Ref Des/Silkscreen Top")
		(7 "B.SilkS" user "Ref Des/Silkscreen Bottom")
		(1 "F.Mask" user "Board Geometry/Soldermask Top")
		(3 "B.Mask" user "Board Geometry/Soldermask Bottom")
		(17 "Dwgs.User" user "User.Drawings")
		(19 "Cmts.User" user "User.Comments")
		(21 "Eco1.User" user "User.Eco1")
		(23 "Eco2.User" user "User.Eco2")
		(25 "Edge.Cuts" user "Board Geometry/Outline")
		(27 "Margin" user)
		(31 "F.CrtYd" user "Package Geometry/Place Bound Top")
		(29 "B.CrtYd" user "Package Geometry/Place Bound Bottom")
		(35 "F.Fab" user "Ref Des/Assembly Top")
		(33 "B.Fab" user "Ref Des/Assembly Bottom")
	)
	(footprint ""
		(layer "B.Cu")
		(at 180.155596 -114.575336 180)
		(property "Reference" "C1154"
			(at 0 0 0)
			(layer "B.SilkS")
			(hide yes)
			(effects
				(font
					(size 1.27 1.27)
				)
				(justify mirror)
			)
		)
		(property "Value" ""
			(at 0 0 0)
			(layer "B.Fab")
			(effects
				(font
					(size 1.27 1.27)
				)
				(justify mirror)
			)
		)
		(duplicate_pad_numbers_are_jumpers no)
		(fp_line
			(start 0.69215 0.2921)
			(end 0.69215 -0.2921)
			(stroke
				(width 0.1524)
				(type default)
			)
			(layer "B.SilkS")
		)
		(fp_line
			(start 0.69215 -0.2921)
			(end -0.69215 -0.2921)
			(stroke
				(width 0.1524)
				(type default)
			)
			(layer "B.SilkS")
		)
		(fp_line
			(start -0.69215 0.2921)
			(end 0.69215 0.2921)
			(stroke
				(width 0.1524)
				(type default)
			)
			(layer "B.SilkS")
		)
		(fp_line
			(start -0.69215 -0.2921)
			(end -0.69215 0.2921)
			(stroke
				(width 0.1524)
				(type default)
			)
			(layer "B.SilkS")
		)
		(fp_line
			(start 0.51435 0.2794)
			(end 0.51435 -0.2794)
			(stroke
				(width 0.1)
				(type default)
			)
			(layer "B.Fab")
		)
		(fp_line
			(start 0.51435 -0.2794)
			(end -0.51435 -0.2794)
			(stroke
				(width 0.1)
				(type default)
			)
			(layer "B.Fab")
		)
		(fp_line
			(start -0.51435 0.2794)
			(end 0.51435 0.2794)
			(stroke
				(width 0.1)
				(type default)
			)
			(layer "B.Fab")
		)
		(fp_line
			(start -0.51435 -0.2794)
			(end -0.51435 0.2794)
			(stroke
				(width 0.1)
				(type default)
			)
			(layer "B.Fab")
		)
		(pad "1" smd circle
			(at 0.40005 0)
			(size 0 0)
			(layers "B.Cu" "B.Mask" "B.Paste")
			(net "VCC_PLD_CORE")
		)
		(pad "2" smd circle
			(at -0.40005 0)
			(size 0 0)
			(layers "B.Cu" "B.Mask" "B.Paste")
			(net "GND")
		)
		(zone
			(layer "B.Cu")
			(hatch none 0.5)
			(connect_pads
				(clearance 0)
			)
			(min_thickness 0.25)
			(keepout
				(tracks not_allowed)
				(vias allowed)
				(pads allowed)
				(copperpour not_allowed)
				(footprints allowed)
			)
			(placement
				(enabled no)
				(sheetname "")
			)
			(fill
				(thermal_gap 0.5)
				(thermal_bridge_width 0.5)
				(island_removal_mode 0)
			)
			(polygon
				(pts
					(xy 179.965096 -114.662966) (xy 180.056536 -114.721132) (xy 180.255926 -114.721132) (xy 180.346096 -114.662966)
					(xy 180.346096 -114.487706) (xy 180.255926 -114.429286) (xy 180.056536 -114.429286) (xy 179.965096 -114.487452)
				)
			)
		)
	)
	(footprint ""
		(layer "B.Cu")
		(at 197.19036 -124.170948 180)
		(property "Reference" "R1106"
			(at 0 0 0)
			(layer "B.SilkS")
			(hide yes)
			(effects
				(font
					(size 1.27 1.27)
				)
				(justify mirror)
			)
		)
		(property "Value" ""
			(at 0 0 0)
			(layer "B.Fab")
			(effects
				(font
					(size 1.27 1.27)
				)
				(justify mirror)
			)
		)
		(duplicate_pad_numbers_are_jumpers no)
		(fp_line
			(start 0.7874 0.4064)
			(end 0.7874 -0.4064)
			(stroke
				(width 0.1524)
				(type default)
			)
			(layer "B.SilkS")
		)
		(fp_line
			(start 0.7874 -0.4064)
			(end -0.7874 -0.4064)
			(stroke
				(width 0.1524)
				(type default)
			)
			(layer "B.SilkS")
		)
		(fp_line
			(start -0.7874 0.4064)
			(end 0.7874 0.4064)
			(stroke
				(width 0.1524)
				(type default)
			)
			(layer "B.SilkS")
		)
		(fp_line
			(start -0.7874 -0.4064)
			(end -0.7874 0.4064)
			(stroke
				(width 0.1524)
				(type default)
			)
			(layer "B.SilkS")
		)
		(fp_line
			(start 0.67945 0.3048)
			(end 0.67945 -0.305054)
			(stroke
				(width 0.1)
				(type default)
			)
			(layer "B.Fab")
		)
		(fp_line
			(start 0.67945 -0.305054)
			(end 0.12065 -0.305054)
			(stroke
				(width 0.1)
				(type default)
			)
			(layer "B.Fab")
		)
		(fp_line
			(start 0.12065 0.3048)
			(end 0.67945 0.3048)
			(stroke
				(width 0.1)
				(type default)
			)
			(layer "B.Fab")
		)
		(fp_line
			(start 0.12065 0.2794)
			(end 0.12065 0.3048)
			(stroke
				(width 0.1)
				(type default)
			)
			(layer "B.Fab")
		)
		(fp_line
			(start 0.12065 -0.2794)
			(end -0.12065 -0.2794)
			(stroke
				(width 0.1)
				(type default)
			)
			(layer "B.Fab")
		)
		(fp_line
			(start 0.12065 -0.305054)
			(end 0.12065 -0.2794)
			(stroke
				(width 0.1)
				(type default)
			)
			(layer "B.Fab")
		)
		(fp_line
			(start -0.120396 0.3048)
			(end -0.120396 0.2794)
			(stroke
				(width 0.1)
				(type default)
			)
			(layer "B.Fab")
		)
		(fp_line
			(start -0.120396 0.2794)
			(end 0.12065 0.2794)
			(stroke
				(width 0.1)
				(type default)
			)
			(layer "B.Fab")
		)
		(fp_line
			(start -0.12065 -0.2794)
			(end -0.12065 -0.3048)
			(stroke
				(width 0.1)
				(type default)
			)
			(layer "B.Fab")
		)
		(fp_line
			(start -0.12065 -0.3048)
			(end -0.67945 -0.3048)
			(stroke
				(width 0.1)
				(type default)
			)
			(layer "B.Fab")
		)
		(fp_line
			(start -0.67945 0.3048)
			(end -0.120396 0.3048)
			(stroke
				(width 0.1)
				(type default)
			)
			(layer "B.Fab")
		)
		(fp_line
			(start -0.67945 -0.3048)
			(end -0.67945 0.3048)
			(stroke
				(width 0.1)
				(type default)
			)
			(layer "B.Fab")
		)
		(pad "1" smd circle
			(at 0.40005 0)
			(size 0 0)
			(layers "B.Cu" "B.Mask" "B.Paste")
			(net "P3V3_AUX")
		)
		(pad "2" smd circle
			(at -0.40005 0)
			(size 0 0)
			(layers "B.Cu" "B.Mask" "B.Paste")
			(net "FM_PLD_REV_R_N")
		)
	)
	(footprint ""
		(layer "B.Cu")
		(at 386.960872 -346.805504 -90)
		(property "Reference" "PC236_P0_8"
			(at 0 0 90)
			(layer "B.SilkS")
			(hide yes)
			(effects
				(font
					(size 1.27 1.27)
				)
				(justify mirror)
			)
		)
		(property "Value" ""
			(at 0 0 90)
			(layer "B.Fab")
			(effects
				(font
					(size 1.27 1.27)
				)
				(justify mirror)
			)
		)
		(duplicate_pad_numbers_are_jumpers no)
		(fp_line
			(start -1.524 0.762)
			(end 1.524 0.762)
			(stroke
				(width 0.1524)
				(type default)
			)
			(layer "B.SilkS")
		)
		(fp_line
			(start 1.524 0.762)
			(end 1.524 -0.762)
			(stroke
				(width 0.1524)
				(type default)
			)
			(layer "B.SilkS")
		)
		(fp_line
			(start -1.524 -0.762)
			(end -1.524 0.762)
			(stroke
				(width 0.1524)
				(type default)
			)
			(layer "B.SilkS")
		)
		(fp_line
			(start 1.524 -0.762)
			(end -1.524 -0.762)
			(stroke
				(width 0.1524)
				(type default)
			)
			(layer "B.SilkS")
		)
		(fp_line
			(start -1.1049 0.724916)
			(end -1.1049 -0.724916)
			(stroke
				(width 0.1)
				(type default)
			)
			(layer "B.Fab")
		)
		(fp_line
			(start 1.1049 0.724916)
			(end -1.1049 0.724916)
			(stroke
				(width 0.1)
				(type default)
			)
			(layer "B.Fab")
		)
		(fp_line
			(start -1.1049 -0.724916)
			(end 1.1049 -0.724916)
			(stroke
				(width 0.1)
				(type default)
			)
			(layer "B.Fab")
		)
		(fp_line
			(start 1.1049 -0.724916)
			(end 1.1049 0.724916)
			(stroke
				(width 0.1)
				(type default)
			)
			(layer "B.Fab")
		)
		(pad "1" smd rect
			(at 0.889 0 270)
			(size 1.016 1.27)
			(layers "B.Cu" "B.Mask" "B.Paste")
			(net "SW_P12V_PVCCIN_CPU0_FLT")
		)
		(pad "2" smd rect
			(at -0.889 0 270)
			(size 1.016 1.27)
			(layers "B.Cu" "B.Mask" "B.Paste")
			(net "GND")
		)
	)
)
